(kicad_pcb
	(version 20221018)
	(generator pcbnew)
	(general
    (thickness 1.586)
  )
	(paper "A4")
	(title_block
    (date "2024-03-26")
    (rev "1.1.3")
		(comment 9 "footprints 108-113 of 146")
	)
	(layers
    (0 "F.Cu" signal)
    (1 "In1.Cu" power)
    (2 "In2.Cu" power)
    (31 "B.Cu" signal)
    (32 "B.Adhes" user "B.Adhesive")
    (33 "F.Adhes" user "F.Adhesive")
    (34 "B.Paste" user)
    (35 "F.Paste" user)
    (36 "B.SilkS" user "B.Silkscreen")
    (37 "F.SilkS" user "F.Silkscreen")
    (38 "B.Mask" user)
    (39 "F.Mask" user)
    (40 "Dwgs.User" user "User.Drawings")
    (41 "Cmts.User" user "User.Comments")
    (42 "Eco1.User" user "User.Eco1")
    (43 "Eco2.User" user "User.Eco2")
    (44 "Edge.Cuts" user)
    (45 "Margin" user)
    (46 "B.CrtYd" user "B.Courtyard")
    (47 "F.CrtYd" user "F.Courtyard")
    (48 "B.Fab" user)
    (49 "F.Fab" user)
  )
	(footprint "scalenode-cm4-baseboard-footprints:R_0402_1005Metric" (layer "B.Cu")
    (at 108.3 69.659 -90)
    (descr "Resistor SMD 0402")
    (tags "resistor SMD 0402")
    (property "Author" "Antmicro")
    (property "License" "Apache-2.0")
    (property "MPN" "CR0402-FX-75R0GLF")
    (property "Manufacturer" "Bourns")
    (property "Sheetfile" "poe.kicad_sch")
    (property "Sheetname" "PoE")
    (property "Tolerance" "1%")
    (property "Val" "75R")
    (property "ki_description" "75R resistor in 0402 package with 1% tolerance")
    (attr smd)
    (fp_text reference "R27" (at -1.059 0.625 90) (layer "B.SilkS")
        (effects (font (size 0.7 0.7) (thickness 0.15)) (justify left bottom mirror))
    )
    (fp_text value "R_75R_0402" (at 0 -1.4 90) (layer "B.Fab")
        (effects (font (size 0.7 0.7) (thickness 0.15)) (justify left bottom mirror))
    )
    (fp_text user "Author: Antmicro" (at -0.95 -4.169 90) (layer "B.Fab") hide
        (effects (font (size 0.7 0.7) (thickness 0.15)) (justify left bottom mirror))
    )
    (fp_text user "License: Apache-2.0" (at -0.95 -5.169 90) (layer "B.Fab") hide
        (effects (font (size 0.7 0.7) (thickness 0.15)) (justify left bottom mirror))
    )
    (fp_text user "${REFERENCE}" (at -0.95 -3.168 90) (layer "B.Fab") hide
        (effects (font (size 0.7 0.7) (thickness 0.15)) (justify left bottom mirror))
    )
    (fp_rect (start -0.95 0.48) (end 0.95 -0.48)
      (stroke (width 0.05) (type solid)) (fill none) (layer "B.CrtYd"))
    (fp_rect (start -0.5 0.25) (end 0.5 -0.25)
      (stroke (width 0.15) (type solid)) (fill none) (layer "B.Fab"))
    (pad "1" smd roundrect (at -0.485 0 270) (size 0.59 0.64) (layers "B.Cu" "B.Paste" "B.Mask") (roundrect_rratio 0.25)
      (net 175 "Net-(C25-Pad2)") (pintype "passive"))
    (pad "2" smd roundrect (at 0.485 0 270) (size 0.59 0.64) (layers "B.Cu" "B.Paste" "B.Mask") (roundrect_rratio 0.25)
      (net 222 "Net-(L3-TCT1)") (pintype "passive"))
  )
	(footprint "scalenode-cm4-baseboard-footprints:TSOT23-6" (layer "B.Cu")
    (at 132 87 180)
    (property "Author" "Antmicro")
    (property "License" "Apache-2.0")
    (property "MPN" "AP62301WU-7")
    (property "Manufacturer" "Diodes Incorporated")
    (property "Sheetfile" "supply.kicad_sch")
    (property "Sheetname" "Supply")
    (attr smd)
    (fp_text reference "U2" (at -1.98 -1.85 180) (layer "B.SilkS")
        (effects (font (size 0.7 0.7) (thickness 0.15)) (justify right bottom mirror))
    )
    (fp_text value "AP62301_TSOT" (at -0.002 -2.91) (layer "B.Fab")
        (effects (font (size 0.7 0.7) (thickness 0.15)) (justify left bottom mirror))
    )
    (fp_text user "Author: Antmicro" (at -1.893 -7.368) (layer "B.Fab") hide
        (effects (font (size 0.7 0.7) (thickness 0.15)) (justify left bottom mirror))
    )
    (fp_text user "License: Apache-2.0" (at -2.231 -4.91) (layer "B.Fab") hide
        (effects (font (size 0.7 0.7) (thickness 0.15)) (justify left bottom mirror))
    )
    (fp_text user "${REFERENCE}" (at -2.231 -6.11) (layer "B.Fab") hide
        (effects (font (size 0.7 0.7) (thickness 0.15)) (justify left bottom mirror))
    )
    (fp_line (start -1.4805 -0.725) (end -1.4795 0.725)
      (stroke (width 0.15) (type solid)) (layer "B.SilkS"))
    (fp_line (start -1.4805 -0.725) (end -1.3905 -0.725)
      (stroke (width 0.15) (type solid)) (layer "B.SilkS"))
    (fp_line (start -1.4795 0.725) (end -1.3905 0.725)
      (stroke (width 0.15) (type solid)) (layer "B.SilkS"))
    (fp_line (start 1.479 -0.73) (end 1.38 -0.73)
      (stroke (width 0.15) (type solid)) (layer "B.SilkS"))
    (fp_line (start 1.48 0.72) (end 1.38 0.72)
      (stroke (width 0.15) (type solid)) (layer "B.SilkS"))
    (fp_line (start 1.48 0.72) (end 1.479 -0.73)
      (stroke (width 0.15) (type solid)) (layer "B.SilkS"))
    (fp_circle (center -1.499 -1.236) (end -1.45 -1.236)
      (stroke (width 0.15) (type solid)) (fill solid) (layer "B.SilkS"))
    (fp_rect (start -1.65 1.61) (end 1.65 -1.61)
      (stroke (width 0.05) (type solid)) (fill none) (layer "B.CrtYd"))
    (fp_line (start -1.527 -0.491) (end -1.527 0.833)
      (stroke (width 0.15) (type solid)) (layer "B.Fab"))
    (fp_line (start -1.527 -0.491) (end -1.102 -0.916)
      (stroke (width 0.15) (type solid)) (layer "B.Fab"))
    (fp_line (start -1.527 0.833) (end 1.523 0.833)
      (stroke (width 0.15) (type solid)) (layer "B.Fab"))
    (fp_line (start -1.102 -0.916) (end 1.523 -0.916)
      (stroke (width 0.15) (type solid)) (layer "B.Fab"))
    (fp_line (start 1.523 0.833) (end 1.523 -0.916)
      (stroke (width 0.15) (type solid)) (layer "B.Fab"))
    (pad "1" smd rect (at -0.952 -1.18 180) (size 0.7 0.8) (layers "B.Cu" "B.Paste" "B.Mask")
      (net 11 "GND") (pinfunction "GND") (pintype "power_in"))
    (pad "2" smd rect (at -0.001 -1.18 180) (size 0.7 0.8) (layers "B.Cu" "B.Paste" "B.Mask")
      (net 19 "Net-(U2-SW)") (pinfunction "SW") (pintype "power_out"))
    (pad "3" smd rect (at 0.947 -1.18 180) (size 0.7 0.8) (layers "B.Cu" "B.Paste" "B.Mask")
      (net 12 "VCC5V0") (pinfunction "VIN") (pintype "power_in"))
    (pad "4" smd rect (at 0.947 1.18 180) (size 0.7 0.8) (layers "B.Cu" "B.Paste" "B.Mask")
      (net 252 "Net-(U2-FB)") (pinfunction "FB") (pintype "input"))
    (pad "5" smd rect (at -0.001 1.18 180) (size 0.7 0.8) (layers "B.Cu" "B.Paste" "B.Mask")
      (net 270 "Net-(U2-EN)") (pinfunction "EN") (pintype "input"))
    (pad "6" smd rect (at -0.952 1.18 180) (size 0.7 0.8) (layers "B.Cu" "B.Paste" "B.Mask")
      (net 22 "Net-(U2-BST)") (pinfunction "BST") (pintype "output"))
  )
	(footprint "scalenode-cm4-baseboard-footprints:R_0402_1005Metric" (layer "B.Cu")
    (at 109.337 69.661 -90)
    (descr "Resistor SMD 0402")
    (tags "resistor SMD 0402")
    (property "Author" "Antmicro")
    (property "License" "Apache-2.0")
    (property "MPN" "CR0402-FX-75R0GLF")
    (property "Manufacturer" "Bourns")
    (property "Sheetfile" "poe.kicad_sch")
    (property "Sheetname" "PoE")
    (property "Tolerance" "1%")
    (property "Val" "75R")
    (property "ki_description" "75R resistor in 0402 package with 1% tolerance")
    (attr smd)
    (fp_text reference "R28" (at -1.136 -1.463 90) (layer "B.SilkS")
        (effects (font (size 0.7 0.7) (thickness 0.15)) (justify left bottom mirror))
    )
    (fp_text value "R_75R_0402" (at 0 -1.4 90) (layer "B.Fab")
        (effects (font (size 0.7 0.7) (thickness 0.15)) (justify left bottom mirror))
    )
    (fp_text user "License: Apache-2.0" (at -0.95 -5.169 90) (layer "B.Fab") hide
        (effects (font (size 0.7 0.7) (thickness 0.15)) (justify left bottom mirror))
    )
    (fp_text user "Author: Antmicro" (at -0.95 -4.169 90) (layer "B.Fab") hide
        (effects (font (size 0.7 0.7) (thickness 0.15)) (justify left bottom mirror))
    )
    (fp_text user "${REFERENCE}" (at -0.95 -3.168 90) (layer "B.Fab") hide
        (effects (font (size 0.7 0.7) (thickness 0.15)) (justify left bottom mirror))
    )
    (fp_rect (start -0.95 0.48) (end 0.95 -0.48)
      (stroke (width 0.05) (type solid)) (fill none) (layer "B.CrtYd"))
    (fp_rect (start -0.5 0.25) (end 0.5 -0.25)
      (stroke (width 0.15) (type solid)) (fill none) (layer "B.Fab"))
    (pad "1" smd roundrect (at -0.485 0 270) (size 0.59 0.64) (layers "B.Cu" "B.Paste" "B.Mask") (roundrect_rratio 0.25)
      (net 175 "Net-(C25-Pad2)") (pintype "passive"))
    (pad "2" smd roundrect (at 0.485 0 270) (size 0.59 0.64) (layers "B.Cu" "B.Paste" "B.Mask") (roundrect_rratio 0.25)
      (net 223 "Net-(L3-TCT2)") (pintype "passive"))
  )
	(footprint "scalenode-cm4-baseboard-footprints:R_0402_1005Metric" (layer "B.Cu")
    (at 109.39 66.496 -90)
    (descr "Resistor SMD 0402")
    (tags "resistor SMD 0402")
    (property "Author" "Antmicro")
    (property "License" "Apache-2.0")
    (property "MPN" "CR0402-FX-75R0GLF")
    (property "Manufacturer" "Bourns")
    (property "Sheetfile" "poe.kicad_sch")
    (property "Sheetname" "PoE")
    (property "Tolerance" "1%")
    (property "Val" "75R")
    (property "ki_description" "75R resistor in 0402 package with 1% tolerance")
    (attr smd)
    (fp_text reference "R29" (at -1.096 -1.46 -90) (layer "B.SilkS")
        (effects (font (size 0.7 0.7) (thickness 0.15)) (justify left bottom mirror))
    )
    (fp_text value "R_75R_0402" (at 0 -1.4 90) (layer "B.Fab")
        (effects (font (size 0.7 0.7) (thickness 0.15)) (justify left bottom mirror))
    )
    (fp_text user "Author: Antmicro" (at -0.95 -4.169 90) (layer "B.Fab") hide
        (effects (font (size 0.7 0.7) (thickness 0.15)) (justify left bottom mirror))
    )
    (fp_text user "License: Apache-2.0" (at -0.95 -5.169 90) (layer "B.Fab") hide
        (effects (font (size 0.7 0.7) (thickness 0.15)) (justify left bottom mirror))
    )
    (fp_text user "${REFERENCE}" (at -0.95 -3.168 90) (layer "B.Fab") hide
        (effects (font (size 0.7 0.7) (thickness 0.15)) (justify left bottom mirror))
    )
    (fp_rect (start -0.95 0.48) (end 0.95 -0.48)
      (stroke (width 0.05) (type solid)) (fill none) (layer "B.CrtYd"))
    (fp_rect (start -0.5 0.25) (end 0.5 -0.25)
      (stroke (width 0.15) (type solid)) (fill none) (layer "B.Fab"))
    (pad "1" smd roundrect (at -0.485 0 270) (size 0.59 0.64) (layers "B.Cu" "B.Paste" "B.Mask") (roundrect_rratio 0.25)
      (net 175 "Net-(C25-Pad2)") (pintype "passive"))
    (pad "2" smd roundrect (at 0.485 0 270) (size 0.59 0.64) (layers "B.Cu" "B.Paste" "B.Mask") (roundrect_rratio 0.25)
      (net 224 "Net-(L3-TCT3)") (pintype "passive"))
  )
	(footprint "scalenode-cm4-baseboard-footprints:Spacer_Drill1mm_H4mm_97730406332R" locked (layer "B.Cu")
    (at 104.59 76.877)
    (property "Author" "Antmicro")
    (property "License" "Apache-2.0")
    (property "MPN" "97730406332R ")
    (property "Manufacturer" "Würth Elektronik")
    (property "Sheetfile" "nvme-ssd.kicad_sch")
    (property "Sheetname" "NVMe SSD")
    (attr smd)
    (fp_text reference "SP6" (at 1.19 -2.047 unlocked) (layer "B.SilkS")
        (effects (font (size 0.7 0.7) (thickness 0.15)) (justify left bottom mirror))
    )
    (fp_text value "Spacer_Drill1mm_H4mm_97730406332R" (at 5.183069 1.377434 180 unlocked) (layer "B.Fab")
        (effects (font (size 0.7 0.7) (thickness 0.15)) (justify left bottom mirror))
    )
    (fp_text user "Author: Antmicro" (at 5.259356 -1.214823) (layer "B.Fab") hide
        (effects (font (size 0.7 0.7) (thickness 0.15)) (justify right bottom mirror))
    )
    (fp_text user "License: Apache-2.0" (at 5.259356 -2.414823) (layer "B.Fab") hide
        (effects (font (size 0.7 0.7) (thickness 0.15)) (justify right bottom mirror))
    )
    (fp_text user "${REFERENCE}" (at 5.259356 -0.014823) (layer "B.Fab") hide
        (effects (font (size 0.7 0.7) (thickness 0.15)) (justify right bottom mirror))
    )
    (fp_line (start -1.849 -0.569) (end -1.849 0.579)
      (stroke (width 0.12) (type solid)) (layer "B.Paste"))
    (fp_line (start -1.748 -0.819) (end -1.748 0.83)
      (stroke (width 0.12) (type solid)) (layer "B.Paste"))
    (fp_line (start -1.65 -0.998) (end -1.65 1.024)
      (stroke (width 0.12) (type solid)) (layer "B.Paste"))
    (fp_line (start -1.549 -1.149) (end -1.549 1.159)
      (stroke (width 0.12) (type solid)) (layer "B.Paste"))
    (fp_line (start -1.448 -1.274) (end -1.448 1.275)
      (stroke (width 0.12) (type solid)) (layer "B.Paste"))
    (fp_line (start -1.349 -1.375) (end -1.349 1.374)
      (stroke (width 0.12) (type solid)) (layer "B.Paste"))
    (fp_line (start -1.248 -1.476) (end -1.248 1.468)
      (stroke (width 0.12) (type solid)) (layer "B.Paste"))
    (fp_line (start -1.15 -1.551) (end -1.15 1.55)
      (stroke (width 0.12) (type solid)) (layer "B.Paste"))
    (fp_line (start -1.049 -1.625) (end -1.049 1.624)
      (stroke (width 0.12) (type solid)) (layer "B.Paste"))
    (fp_line (start -0.95 -1.676) (end -0.95 1.679)
      (stroke (width 0.12) (type solid)) (layer "B.Paste"))
    (fp_line (start -0.849 -1.726) (end -0.849 1.739)
      (stroke (width 0.12) (type solid)) (layer "B.Paste"))
    (fp_line (start -0.748 -1.774) (end -0.748 1.778)
      (stroke (width 0.12) (type solid)) (layer "B.Paste"))
    (fp_line (start -0.65 -1.825) (end -0.65 1.823)
      (stroke (width 0.12) (type solid)) (layer "B.Paste"))
    (fp_line (start -0.551 1.87) (end -0.551 -1.86)
      (stroke (width 0.12) (type solid)) (layer "B.Paste"))
    (fp_line (start 0.551 -1.87) (end 0.551 1.859)
      (stroke (width 0.12) (type solid)) (layer "B.Paste"))
    (fp_line (start 0.65 1.823) (end 0.65 -1.825)
      (stroke (width 0.12) (type solid)) (layer "B.Paste"))
    (fp_line (start 0.749 1.775) (end 0.749 -1.779)
      (stroke (width 0.12) (type solid)) (layer "B.Paste"))
    (fp_line (start 0.849 1.724) (end 0.849 -1.74)
      (stroke (width 0.12) (type solid)) (layer "B.Paste"))
    (fp_line (start 0.95 1.675) (end 0.95 -1.679)
      (stroke (width 0.12) (type solid)) (layer "B.Paste"))
    (fp_line (start 1.051 1.624) (end 1.051 -1.625)
      (stroke (width 0.12) (type solid)) (layer "B.Paste"))
    (fp_line (start 1.149 1.55) (end 1.149 -1.551)
      (stroke (width 0.12) (type solid)) (layer "B.Paste"))
    (fp_line (start 1.25 1.474) (end 1.25 -1.469)
      (stroke (width 0.12) (type solid)) (layer "B.Paste"))
    (fp_line (start 1.351 1.374) (end 1.351 -1.375)
      (stroke (width 0.12) (type solid)) (layer "B.Paste"))
    (fp_line (start 1.45 1.275) (end 1.45 -1.274)
      (stroke (width 0.12) (type solid)) (layer "B.Paste"))
    (fp_line (start 1.551 1.15) (end 1.551 -1.16)
      (stroke (width 0.12) (type solid)) (layer "B.Paste"))
    (fp_line (start 1.649 0.999) (end 1.649 -1.024)
      (stroke (width 0.12) (type solid)) (layer "B.Paste"))
    (fp_line (start 1.75 0.82) (end 1.75 -0.83)
      (stroke (width 0.12) (type solid)) (layer "B.Paste"))
    (fp_line (start 1.851 0.57) (end 1.851 -0.578)
      (stroke (width 0.12) (type solid)) (layer "B.Paste"))
    (fp_arc (start -0.551 1.874) (mid -1.952999 0.00274) (end -0.557 -1.873)
      (stroke (width 0.1) (type solid)) (layer "B.Paste"))
    (fp_arc (start 0.551 -1.875) (mid 1.953999 -0.002741) (end 0.557 1.874)
      (stroke (width 0.1) (type solid)) (layer "B.Paste"))
    (fp_circle (center 0.001 2.2) (end 0.051 2.2)
      (stroke (width 0.15) (type solid)) (fill solid) (layer "B.SilkS"))
    (fp_rect (start -1.9 1.9) (end 1.89 -1.89)
      (stroke (width 0.05) (type solid)) (fill none) (layer "B.CrtYd"))
    (pad "1" thru_hole custom locked (at 0.001 0) (size 4 4) (drill 1) (layers "B.Cu" "B.Mask")
      (net 221 "unconnected-(SP6-Pad1)") (pinfunction "1") (pintype "passive+no_connect") (solder_paste_margin -1.2) (zone_connect 0)
      (options (clearance outline) (anchor circle))
      (primitives
      ))
  )
	(footprint "scalenode-cm4-baseboard-footprints:C_0402_1005Metric" (layer "B.Cu")
    (at 134.5 86.25 90)
    (descr "Capacitor SMD 0402")
    (tags "capacitor SMD 0402")
    (property "Author" "Antmicro")
    (property "Dielectric" "X5R")
    (property "License" "Apache-2.0")
    (property "MPN" "GRM155R61H104KE14D")
    (property "Manufacturer" "Murata")
    (property "Sheetfile" "supply.kicad_sch")
    (property "Sheetname" "Supply")
    (property "Val" "100n")
    (property "Voltage" "50V")
    (property "ki_description" " ")
    (attr smd)
    (fp_text reference "C17" (at 1.075 1.475 90) (layer "B.SilkS")
        (effects (font (size 0.7 0.7) (thickness 0.15)) (justify left bottom mirror))
    )
    (fp_text value "C_100n_0402" (at 0 -1.4 90) (layer "B.Fab")
        (effects (font (size 0.7 0.7) (thickness 0.15)) (justify right bottom mirror))
    )
    (fp_text user "License: Apache-2.0" (at -0.932 -5.17 90) (layer "B.Fab") hide
        (effects (font (size 0.7 0.7) (thickness 0.15)) (justify right bottom mirror))
    )
    (fp_text user "${REFERENCE}" (at -0.932 -3.168 90) (layer "B.Fab") hide
        (effects (font (size 0.7 0.7) (thickness 0.15)) (justify right bottom mirror))
    )
    (fp_text user "Author: Antmicro" (at -0.932 -4.17 90) (layer "B.Fab") hide
        (effects (font (size 0.7 0.7) (thickness 0.15)) (justify right bottom mirror))
    )
    (fp_rect (start -0.94 0.47) (end 0.94 -0.47)
      (stroke (width 0.05) (type solid)) (fill none) (layer "B.CrtYd"))
    (fp_rect (start -0.499 0.249) (end 0.499 -0.249)
      (stroke (width 0.15) (type solid)) (fill none) (layer "B.Fab"))
    (pad "1" smd roundrect (at -0.484 0 90) (size 0.59 0.64) (layers "B.Cu" "B.Paste" "B.Mask") (roundrect_rratio 0.25)
      (net 19 "Net-(U2-SW)") (pintype "passive"))
    (pad "2" smd roundrect (at 0.484 0 90) (size 0.59 0.64) (layers "B.Cu" "B.Paste" "B.Mask") (roundrect_rratio 0.25)
      (net 22 "Net-(U2-BST)") (pintype "passive"))
  )
)
